FILE_TYPE = MACRO_DRAWING;
SET COLOR_WIRE YELLOW;
SET COLOR_PROP MONO;
SET COLOR_DOT WHITE;
SET COLOR_ARC YELLOW;
SET COLOR_BODY GREEN;
SET COLOR_NOTE MONO;
SET PROP_DISPLAY VALUE;
SET PAGE_NUMBER P20;
FORCEADD INTEL_CORP_BPAGE..1
(0 0);
FORCEPROP 1 LAST CUSTOM_TXT_CDS <CURRENT_DESIGN_SHEET> OF <TOTAL_DESIGN_SHEETS>
J 0
(-500 25);
PAINT GREEN (-500 25);
FORCEPROP 1 LAST CUSTOM_TXT_CDS <CON_LAST_MODIFIED>
J 0
(-1925 350);
PAINT GREEN (-1925 350);
FORCEPROP 2 LAST CUSTOM_TXT_CDS <XR_PAGE_TITLE>
J 0
(-7890 5250);
DISPLAY 0.638298 (-7890 5250);
PAINT PINK (-7890 5250);
DISPLAY INVISIBLE (-7890 5250);
FORCEPROP 1 LAST SCH_REV 2.420
J 0
(-250 150);
DISPLAY 0.978723 (-250 150);
PAINT YELLOW (-250 150);
FORCEPROP 1 LAST SCH_DEPT BESD
J 1
(-4450 100);
DISPLAY 1.212766 (-4450 100);
PAINT YELLOW (-4450 100);
FORCEPROP 1 LAST SCH_NUMBER H4694802
J 0
(-1300 150);
DISPLAY 1.212766 (-1300 150);
PAINT YELLOW (-1300 150);
FORCEPROP 1 LAST SCH_TITLE MISC. VOLTAGE INFO
J 0
(-7950 50);
DISPLAY 1.212766 (-7950 50);
PAINT ORANGE (-7950 50);
FORCEPROP 1 LAST SCH_ADDRESS1 2200 Mission College Blvd.
J 0
(-3975 125);
DISPLAY 0.617021 (-3975 125);
PAINT GREEN (-3975 125);
FORCEPROP 1 LAST SCH_ADDRESS2 P.O. BOX 58119
J 0
(-3975 75);
DISPLAY 0.617021 (-3975 75);
PAINT GREEN (-3975 75);
FORCEPROP 1 LAST SCH_ADDRESS3 Santa Clara, CA 95052-8119
J 0
(-3975 25);
DISPLAY 0.617021 (-3975 25);
PAINT GREEN (-3975 25);
FORCEPROP 1 LAST COMMENT_BODY TRUE
J 0
(12 12);
DISPLAY 0.468085 (12 12);
PAINT GREEN (12 12);
DISPLAY INVISIBLE (12 12);
FORCEPROP 2 LAST PAGE_BORDER TRUE
J 0
(-7890 5250);
DISPLAY 0.638298 (-7890 5250);
PAINT PINK (-7890 5250);
DISPLAY INVISIBLE (-7890 5250);
FORCEPROP 2 LAST CDS_LIB mstr_symbols
J 0
(0 0);
PAINT MONO (0 0);
DISPLAY INVISIBLE (0 0);
FORCEPROP 1 LAST CDS_CON_LAST_MODIFIED Tue Dec 01 11:47:59 2015
J 0
(-1425 325);
PAINT ORANGE (-1425 325);
DISPLAY INVISIBLE (-1425 325);
FORCEPROP 2 LAST CDS_XR_PAGE_TITLE CR-20 : @BASEBOARD_FAB2_LIB.BASEBOARD_FAB2(SCH_1):PAGE20
J 0
(-7890 5250);
DISPLAY 0.638298 (-7890 5250);
PAINT PINK (-7890 5250);
DISPLAY INVISIBLE (-7890 5250);
FORCENOTE
$CDS_IMAGE|MISC.jpg|3444|2097
(-4225 3625) 0;
DISPLAY CENTER (-4225 3625);
PAINT MONO (-4225 3625);
QUIT
